(kicad_pcb
	(version 20260206)
	(generator "pcbnew")
	(generator_version "10.0")
	(general
		(thickness 1.6)
		(legacy_teardrops no)
	)
	(paper "A4")
	(title_block
		(title "01162023_DA0F0TEBIF0_F0T_Expander_BD_F_brd_V02_OCP.brd")
		(comment 1 "Grand Teton / footprints 3035-3040 of 9728")
	)
	(layers
		(0 "F.Cu" signal "TOP")
		(4 "In1.Cu" signal "GND")
		(6 "In2.Cu" signal "VCC")
		(8 "In3.Cu" signal "VCC1")
		(10 "In4.Cu" signal "GND1")
		(12 "In5.Cu" signal "IN1")
		(14 "In6.Cu" signal "GND2")
		(16 "In7.Cu" signal "IN2")
		(18 "In8.Cu" signal "GND3")
		(20 "In9.Cu" signal "IN3")
		(22 "In10.Cu" signal "GND4")
		(24 "In11.Cu" signal "IN4")
		(26 "In12.Cu" signal "GND5")
		(28 "In13.Cu" signal "IN5")
		(30 "In14.Cu" signal "GND6")
		(32 "In15.Cu" signal "IN6")
		(34 "In16.Cu" signal "GND7")
		(2 "B.Cu" signal "BOTTOM")
		(9 "F.Adhes" user "F.Adhesive")
		(11 "B.Adhes" user "B.Adhesive")
		(13 "F.Paste" user "Package Geometry/Pastemask Top")
		(15 "B.Paste" user "Package Geometry/Pastemask Bottom")
		(5 "F.SilkS" user "Ref Des/Silkscreen Top")
		(7 "B.SilkS" user "Ref Des/Silkscreen Bottom")
		(1 "F.Mask" user "Board Geometry/Soldermask Top")
		(3 "B.Mask" user "Board Geometry/Soldermask Bottom")
		(17 "Dwgs.User" user "User.Drawings")
		(19 "Cmts.User" user "User.Comments")
		(21 "Eco1.User" user "User.Eco1")
		(23 "Eco2.User" user "User.Eco2")
		(25 "Edge.Cuts" user "Board Geometry/Outline")
		(27 "Margin" user)
		(31 "F.CrtYd" user "Package Geometry/Place Bound Top")
		(29 "B.CrtYd" user "Package Geometry/Place Bound Bottom")
		(35 "F.Fab" user "Ref Des/Assembly Top")
		(33 "B.Fab" user "Ref Des/Assembly Bottom")
	)
	(footprint ""
		(layer "F.Cu")
		(at 288.726626 -53.697124 -90)
		(property "Reference" "PC558"
			(at 0 0 270)
			(layer "F.SilkS")
			(hide yes)
			(effects
				(font
					(size 1.27 1.27)
				)
			)
		)
		(property "Value" ""
			(at 0 0 270)
			(layer "F.Fab")
			(effects
				(font
					(size 1.27 1.27)
				)
			)
		)
		(duplicate_pad_numbers_are_jumpers no)
		(fp_line
			(start -0.7874 0.4064)
			(end -0.7874 -0.4064)
			(stroke
				(width 0.1524)
				(type default)
			)
			(layer "F.SilkS")
		)
		(fp_line
			(start 0.7874 0.4064)
			(end -0.7874 0.4064)
			(stroke
				(width 0.1524)
				(type default)
			)
			(layer "F.SilkS")
		)
		(fp_line
			(start -0.7874 -0.4064)
			(end 0.7874 -0.4064)
			(stroke
				(width 0.1524)
				(type default)
			)
			(layer "F.SilkS")
		)
		(fp_line
			(start 0.7874 -0.4064)
			(end 0.7874 0.4064)
			(stroke
				(width 0.1524)
				(type default)
			)
			(layer "F.SilkS")
		)
		(fp_line
			(start -0.67945 0.3048)
			(end -0.67945 -0.305054)
			(stroke
				(width 0.1)
				(type default)
			)
			(layer "F.Fab")
		)
		(fp_line
			(start -0.12065 0.3048)
			(end -0.67945 0.3048)
			(stroke
				(width 0.1)
				(type default)
			)
			(layer "F.Fab")
		)
		(fp_line
			(start 0.120396 0.3048)
			(end 0.120396 0.2794)
			(stroke
				(width 0.1)
				(type default)
			)
			(layer "F.Fab")
		)
		(fp_line
			(start 0.67945 0.3048)
			(end 0.120396 0.3048)
			(stroke
				(width 0.1)
				(type default)
			)
			(layer "F.Fab")
		)
		(fp_line
			(start -0.12065 0.2794)
			(end -0.12065 0.3048)
			(stroke
				(width 0.1)
				(type default)
			)
			(layer "F.Fab")
		)
		(fp_line
			(start 0.120396 0.2794)
			(end -0.12065 0.2794)
			(stroke
				(width 0.1)
				(type default)
			)
			(layer "F.Fab")
		)
		(fp_line
			(start -0.12065 -0.2794)
			(end 0.12065 -0.2794)
			(stroke
				(width 0.1)
				(type default)
			)
			(layer "F.Fab")
		)
		(fp_line
			(start 0.12065 -0.2794)
			(end 0.12065 -0.3048)
			(stroke
				(width 0.1)
				(type default)
			)
			(layer "F.Fab")
		)
		(fp_line
			(start 0.12065 -0.3048)
			(end 0.67945 -0.3048)
			(stroke
				(width 0.1)
				(type default)
			)
			(layer "F.Fab")
		)
		(fp_line
			(start 0.67945 -0.3048)
			(end 0.67945 0.3048)
			(stroke
				(width 0.1)
				(type default)
			)
			(layer "F.Fab")
		)
		(fp_line
			(start -0.67945 -0.305054)
			(end -0.12065 -0.305054)
			(stroke
				(width 0.1)
				(type default)
			)
			(layer "F.Fab")
		)
		(fp_line
			(start -0.12065 -0.305054)
			(end -0.12065 -0.2794)
			(stroke
				(width 0.1)
				(type default)
			)
			(layer "F.Fab")
		)
		(pad "1" smd circle
			(at -0.40005 0 270)
			(size 0 0)
			(layers "F.Cu" "F.Mask" "F.Paste")
			(net "P3V3_AUX")
		)
		(pad "2" smd circle
			(at 0.40005 0 270)
			(size 0 0)
			(layers "F.Cu" "F.Mask" "F.Paste")
			(net "GND")
		)
	)
	(footprint ""
		(layer "F.Cu")
		(at 101.359208 -224.224342 90)
		(property "Reference" "PC296"
			(at 0 0 90)
			(layer "F.SilkS")
			(hide yes)
			(effects
				(font
					(size 1.27 1.27)
				)
			)
		)
		(property "Value" ""
			(at 0 0 90)
			(layer "F.Fab")
			(effects
				(font
					(size 1.27 1.27)
				)
			)
		)
		(duplicate_pad_numbers_are_jumpers no)
		(fp_line
			(start 0.7874 -0.4064)
			(end 0.7874 0.4064)
			(stroke
				(width 0.1524)
				(type default)
			)
			(layer "F.SilkS")
		)
		(fp_line
			(start -0.7874 -0.4064)
			(end 0.7874 -0.4064)
			(stroke
				(width 0.1524)
				(type default)
			)
			(layer "F.SilkS")
		)
		(fp_line
			(start 0.7874 0.4064)
			(end -0.7874 0.4064)
			(stroke
				(width 0.1524)
				(type default)
			)
			(layer "F.SilkS")
		)
		(fp_line
			(start -0.7874 0.4064)
			(end -0.7874 -0.4064)
			(stroke
				(width 0.1524)
				(type default)
			)
			(layer "F.SilkS")
		)
		(fp_line
			(start -0.12065 -0.305054)
			(end -0.12065 -0.2794)
			(stroke
				(width 0.1)
				(type default)
			)
			(layer "F.Fab")
		)
		(fp_line
			(start -0.67945 -0.305054)
			(end -0.12065 -0.305054)
			(stroke
				(width 0.1)
				(type default)
			)
			(layer "F.Fab")
		)
		(fp_line
			(start 0.67945 -0.3048)
			(end 0.67945 0.3048)
			(stroke
				(width 0.1)
				(type default)
			)
			(layer "F.Fab")
		)
		(fp_line
			(start 0.12065 -0.3048)
			(end 0.67945 -0.3048)
			(stroke
				(width 0.1)
				(type default)
			)
			(layer "F.Fab")
		)
		(fp_line
			(start 0.12065 -0.2794)
			(end 0.12065 -0.3048)
			(stroke
				(width 0.1)
				(type default)
			)
			(layer "F.Fab")
		)
		(fp_line
			(start -0.12065 -0.2794)
			(end 0.12065 -0.2794)
			(stroke
				(width 0.1)
				(type default)
			)
			(layer "F.Fab")
		)
		(fp_line
			(start 0.120396 0.2794)
			(end -0.12065 0.2794)
			(stroke
				(width 0.1)
				(type default)
			)
			(layer "F.Fab")
		)
		(fp_line
			(start -0.12065 0.2794)
			(end -0.12065 0.3048)
			(stroke
				(width 0.1)
				(type default)
			)
			(layer "F.Fab")
		)
		(fp_line
			(start 0.67945 0.3048)
			(end 0.120396 0.3048)
			(stroke
				(width 0.1)
				(type default)
			)
			(layer "F.Fab")
		)
		(fp_line
			(start 0.120396 0.3048)
			(end 0.120396 0.2794)
			(stroke
				(width 0.1)
				(type default)
			)
			(layer "F.Fab")
		)
		(fp_line
			(start -0.12065 0.3048)
			(end -0.67945 0.3048)
			(stroke
				(width 0.1)
				(type default)
			)
			(layer "F.Fab")
		)
		(fp_line
			(start -0.67945 0.3048)
			(end -0.67945 -0.305054)
			(stroke
				(width 0.1)
				(type default)
			)
			(layer "F.Fab")
		)
		(pad "1" smd circle
			(at -0.40005 0 90)
			(size 0 0)
			(layers "F.Cu" "F.Mask" "F.Paste")
			(net "P1V8_PEX_REF")
		)
		(pad "2" smd circle
			(at 0.40005 0 90)
			(size 0 0)
			(layers "F.Cu" "F.Mask" "F.Paste")
			(net "GND")
		)
	)
	(footprint ""
		(layer "F.Cu")
		(at 207.134206 -306.074572 90)
		(property "Reference" "R1306"
			(at 0 0 90)
			(layer "F.SilkS")
			(hide yes)
			(effects
				(font
					(size 1.27 1.27)
				)
			)
		)
		(property "Value" ""
			(at 0 0 90)
			(layer "F.Fab")
			(effects
				(font
					(size 1.27 1.27)
				)
			)
		)
		(duplicate_pad_numbers_are_jumpers no)
		(fp_line
			(start 0.7874 -0.4064)
			(end 0.7874 0.4064)
			(stroke
				(width 0.1524)
				(type default)
			)
			(layer "F.SilkS")
		)
		(fp_line
			(start -0.7874 -0.4064)
			(end 0.7874 -0.4064)
			(stroke
				(width 0.1524)
				(type default)
			)
			(layer "F.SilkS")
		)
		(fp_line
			(start 0.7874 0.4064)
			(end -0.7874 0.4064)
			(stroke
				(width 0.1524)
				(type default)
			)
			(layer "F.SilkS")
		)
		(fp_line
			(start -0.7874 0.4064)
			(end -0.7874 -0.4064)
			(stroke
				(width 0.1524)
				(type default)
			)
			(layer "F.SilkS")
		)
		(fp_line
			(start -0.12065 -0.305054)
			(end -0.12065 -0.2794)
			(stroke
				(width 0.1)
				(type default)
			)
			(layer "F.Fab")
		)
		(fp_line
			(start -0.67945 -0.305054)
			(end -0.12065 -0.305054)
			(stroke
				(width 0.1)
				(type default)
			)
			(layer "F.Fab")
		)
		(fp_line
			(start 0.67945 -0.3048)
			(end 0.67945 0.3048)
			(stroke
				(width 0.1)
				(type default)
			)
			(layer "F.Fab")
		)
		(fp_line
			(start 0.12065 -0.3048)
			(end 0.67945 -0.3048)
			(stroke
				(width 0.1)
				(type default)
			)
			(layer "F.Fab")
		)
		(fp_line
			(start 0.12065 -0.2794)
			(end 0.12065 -0.3048)
			(stroke
				(width 0.1)
				(type default)
			)
			(layer "F.Fab")
		)
		(fp_line
			(start -0.12065 -0.2794)
			(end 0.12065 -0.2794)
			(stroke
				(width 0.1)
				(type default)
			)
			(layer "F.Fab")
		)
		(fp_line
			(start 0.120396 0.2794)
			(end -0.12065 0.2794)
			(stroke
				(width 0.1)
				(type default)
			)
			(layer "F.Fab")
		)
		(fp_line
			(start -0.12065 0.2794)
			(end -0.12065 0.3048)
			(stroke
				(width 0.1)
				(type default)
			)
			(layer "F.Fab")
		)
		(fp_line
			(start 0.67945 0.3048)
			(end 0.120396 0.3048)
			(stroke
				(width 0.1)
				(type default)
			)
			(layer "F.Fab")
		)
		(fp_line
			(start 0.120396 0.3048)
			(end 0.120396 0.2794)
			(stroke
				(width 0.1)
				(type default)
			)
			(layer "F.Fab")
		)
		(fp_line
			(start -0.12065 0.3048)
			(end -0.67945 0.3048)
			(stroke
				(width 0.1)
				(type default)
			)
			(layer "F.Fab")
		)
		(fp_line
			(start -0.67945 0.3048)
			(end -0.67945 -0.305054)
			(stroke
				(width 0.1)
				(type default)
			)
			(layer "F.Fab")
		)
		(pad "1" smd circle
			(at -0.40005 0 90)
			(size 0 0)
			(layers "F.Cu" "F.Mask" "F.Paste")
			(net "PEX1_SPARE1")
		)
		(pad "2" smd circle
			(at 0.40005 0 90)
			(size 0 0)
			(layers "F.Cu" "F.Mask" "F.Paste")
			(net "P1V8_PEX")
		)
	)
	(footprint ""
		(layer "F.Cu")
		(at 453.024494 -119.77624)
		(property "Reference" "Q219"
			(at 0.447294 -1.91008 0)
			(unlocked yes)
			(layer "F.SilkS")
			(effects
				(font
					(size 0.7874 0.5842)
					(thickness 0.1524)
				)
			)
		)
		(property "Value" ""
			(at 0 0 0)
			(layer "F.Fab")
			(effects
				(font
					(size 1.27 1.27)
				)
			)
		)
		(duplicate_pad_numbers_are_jumpers no)
		(fp_line
			(start -1.376172 -1.199896)
			(end -0.508 -1.199896)
			(stroke
				(width 0.1524)
				(type default)
			)
			(layer "F.SilkS")
		)
		(fp_line
			(start -1.376172 1.199896)
			(end -1.376172 -1.199896)
			(stroke
				(width 0.1524)
				(type default)
			)
			(layer "F.SilkS")
		)
		(fp_line
			(start -0.508 -1.199896)
			(end 0 -0.762)
			(stroke
				(width 0.1524)
				(type default)
			)
			(layer "F.SilkS")
		)
		(fp_line
			(start 0 -0.762)
			(end 0.508 -1.199896)
			(stroke
				(width 0.1524)
				(type default)
			)
			(layer "F.SilkS")
		)
		(fp_line
			(start 0.508 -1.199896)
			(end 1.376172 -1.199896)
			(stroke
				(width 0.1524)
				(type default)
			)
			(layer "F.SilkS")
		)
		(fp_line
			(start 1.376172 -1.199896)
			(end 1.376172 1.199896)
			(stroke
				(width 0.1524)
				(type default)
			)
			(layer "F.SilkS")
		)
		(fp_line
			(start 1.376172 1.199896)
			(end -1.376172 1.199896)
			(stroke
				(width 0.1524)
				(type default)
			)
			(layer "F.SilkS")
		)
		(fp_poly
			(pts
				(xy -1.121156 -1.288034) (xy -1.390396 -2.096262) (xy -1.929384 -1.557274)
			)
			(stroke
				(width 0)
				(type default)
			)
			(fill yes)
			(layer "F.SilkS")
		)
		(fp_line
			(start -0.674878 -1.100074)
			(end 0.674878 -1.100074)
			(stroke
				(width 0.1)
				(type default)
			)
			(layer "F.Fab")
		)
		(fp_line
			(start -0.674878 1.100074)
			(end -0.674878 -1.100074)
			(stroke
				(width 0.1)
				(type default)
			)
			(layer "F.Fab")
		)
		(fp_line
			(start 0.674878 -1.100074)
			(end 0.674878 1.100074)
			(stroke
				(width 0.1)
				(type default)
			)
			(layer "F.Fab")
		)
		(fp_line
			(start 0.674878 1.100074)
			(end -0.674878 1.100074)
			(stroke
				(width 0.1)
				(type default)
			)
			(layer "F.Fab")
		)
		(fp_poly
			(pts
				(xy -1.4605 -0.7493) (xy -2.2225 -1.1303) (xy -2.2225 -0.3683)
			)
			(stroke
				(width 0)
				(type default)
			)
			(fill yes)
			(layer "F.Fab")
		)
		(pad "1" smd rect
			(at -0.899922 -0.750062 270)
			(size 0.6096 0.6096)
			(layers "F.Cu" "F.Mask" "F.Paste")
			(net "GND")
		)
		(pad "2" smd rect
			(at -0.899922 0 270)
			(size 0.4064 0.6096)
			(layers "F.Cu" "F.Mask" "F.Paste")
			(net "P3V3_NIC7_PG_G1")
		)
		(pad "3" smd rect
			(at -0.899922 0.750062 270)
			(size 0.6096 0.6096)
			(layers "F.Cu" "F.Mask" "F.Paste")
			(net "PWRGD_P3V3_NIC7_D")
		)
		(pad "4" smd rect
			(at 0.899922 0.750062 270)
			(size 0.6096 0.6096)
			(layers "F.Cu" "F.Mask" "F.Paste")
			(net "GND")
		)
		(pad "5" smd rect
			(at 0.899922 0 270)
			(size 0.4064 0.6096)
			(layers "F.Cu" "F.Mask" "F.Paste")
			(net "P3V3_NIC7_PG_G2")
		)
		(pad "6" smd rect
			(at 0.899922 -0.750062 270)
			(size 0.6096 0.6096)
			(layers "F.Cu" "F.Mask" "F.Paste")
			(net "P3V3_NIC7_PG_G2")
		)
	)
	(footprint ""
		(layer "F.Cu")
		(at 377.175268 -63.086234)
		(property "Reference" "R6019"
			(at 0 0 0)
			(layer "F.SilkS")
			(hide yes)
			(effects
				(font
					(size 1.27 1.27)
				)
			)
		)
		(property "Value" ""
			(at 0 0 0)
			(layer "F.Fab")
			(effects
				(font
					(size 1.27 1.27)
				)
			)
		)
		(duplicate_pad_numbers_are_jumpers no)
		(fp_line
			(start -0.7874 -0.4064)
			(end 0.7874 -0.4064)
			(stroke
				(width 0.1524)
				(type default)
			)
			(layer "F.SilkS")
		)
		(fp_line
			(start -0.7874 0.4064)
			(end -0.7874 -0.4064)
			(stroke
				(width 0.1524)
				(type default)
			)
			(layer "F.SilkS")
		)
		(fp_line
			(start 0.7874 -0.4064)
			(end 0.7874 0.4064)
			(stroke
				(width 0.1524)
				(type default)
			)
			(layer "F.SilkS")
		)
		(fp_line
			(start 0.7874 0.4064)
			(end -0.7874 0.4064)
			(stroke
				(width 0.1524)
				(type default)
			)
			(layer "F.SilkS")
		)
		(fp_line
			(start -0.67945 -0.305054)
			(end -0.12065 -0.305054)
			(stroke
				(width 0.1)
				(type default)
			)
			(layer "F.Fab")
		)
		(fp_line
			(start -0.67945 0.3048)
			(end -0.67945 -0.305054)
			(stroke
				(width 0.1)
				(type default)
			)
			(layer "F.Fab")
		)
		(fp_line
			(start -0.12065 -0.305054)
			(end -0.12065 -0.2794)
			(stroke
				(width 0.1)
				(type default)
			)
			(layer "F.Fab")
		)
		(fp_line
			(start -0.12065 -0.2794)
			(end 0.12065 -0.2794)
			(stroke
				(width 0.1)
				(type default)
			)
			(layer "F.Fab")
		)
		(fp_line
			(start -0.12065 0.2794)
			(end -0.12065 0.3048)
			(stroke
				(width 0.1)
				(type default)
			)
			(layer "F.Fab")
		)
		(fp_line
			(start -0.12065 0.3048)
			(end -0.67945 0.3048)
			(stroke
				(width 0.1)
				(type default)
			)
			(layer "F.Fab")
		)
		(fp_line
			(start 0.120396 0.2794)
			(end -0.12065 0.2794)
			(stroke
				(width 0.1)
				(type default)
			)
			(layer "F.Fab")
		)
		(fp_line
			(start 0.120396 0.3048)
			(end 0.120396 0.2794)
			(stroke
				(width 0.1)
				(type default)
			)
			(layer "F.Fab")
		)
		(fp_line
			(start 0.12065 -0.3048)
			(end 0.67945 -0.3048)
			(stroke
				(width 0.1)
				(type default)
			)
			(layer "F.Fab")
		)
		(fp_line
			(start 0.12065 -0.2794)
			(end 0.12065 -0.3048)
			(stroke
				(width 0.1)
				(type default)
			)
			(layer "F.Fab")
		)
		(fp_line
			(start 0.67945 -0.3048)
			(end 0.67945 0.3048)
			(stroke
				(width 0.1)
				(type default)
			)
			(layer "F.Fab")
		)
		(fp_line
			(start 0.67945 0.3048)
			(end 0.120396 0.3048)
			(stroke
				(width 0.1)
				(type default)
			)
			(layer "F.Fab")
		)
		(pad "1" smd circle
			(at -0.40005 0)
			(size 0 0)
			(layers "F.Cu" "F.Mask" "F.Paste")
			(net "P12V_SSD13_R")
		)
		(pad "2" smd circle
			(at 0.40005 0)
			(size 0 0)
			(layers "F.Cu" "F.Mask" "F.Paste")
			(net "P12V_SSD13_PG_G1")
		)
	)
	(footprint ""
		(layer "F.Cu")
		(at 252.875034 -56.977534 180)
		(property "Reference" "PC400"
			(at 0 0 180)
			(layer "F.SilkS")
			(hide yes)
			(effects
				(font
					(size 1.27 1.27)
				)
			)
		)
		(property "Value" ""
			(at 0 0 180)
			(layer "F.Fab")
			(effects
				(font
					(size 1.27 1.27)
				)
			)
		)
		(duplicate_pad_numbers_are_jumpers no)
		(fp_line
			(start 0.7874 0.4064)
			(end -0.7874 0.4064)
			(stroke
				(width 0.1524)
				(type default)
			)
			(layer "F.SilkS")
		)
		(fp_line
			(start 0.7874 -0.4064)
			(end 0.7874 0.4064)
			(stroke
				(width 0.1524)
				(type default)
			)
			(layer "F.SilkS")
		)
		(fp_line
			(start -0.7874 0.4064)
			(end -0.7874 -0.4064)
			(stroke
				(width 0.1524)
				(type default)
			)
			(layer "F.SilkS")
		)
		(fp_line
			(start -0.7874 -0.4064)
			(end 0.7874 -0.4064)
			(stroke
				(width 0.1524)
				(type default)
			)
			(layer "F.SilkS")
		)
		(fp_line
			(start 0.67945 0.3048)
			(end 0.120396 0.3048)
			(stroke
				(width 0.1)
				(type default)
			)
			(layer "F.Fab")
		)
		(fp_line
			(start 0.67945 -0.3048)
			(end 0.67945 0.3048)
			(stroke
				(width 0.1)
				(type default)
			)
			(layer "F.Fab")
		)
		(fp_line
			(start 0.12065 -0.2794)
			(end 0.12065 -0.3048)
			(stroke
				(width 0.1)
				(type default)
			)
			(layer "F.Fab")
		)
		(fp_line
			(start 0.12065 -0.3048)
			(end 0.67945 -0.3048)
			(stroke
				(width 0.1)
				(type default)
			)
			(layer "F.Fab")
		)
		(fp_line
			(start 0.120396 0.3048)
			(end 0.120396 0.2794)
			(stroke
				(width 0.1)
				(type default)
			)
			(layer "F.Fab")
		)
		(fp_line
			(start 0.120396 0.2794)
			(end -0.12065 0.2794)
			(stroke
				(width 0.1)
				(type default)
			)
			(layer "F.Fab")
		)
		(fp_line
			(start -0.12065 0.3048)
			(end -0.67945 0.3048)
			(stroke
				(width 0.1)
				(type default)
			)
			(layer "F.Fab")
		)
		(fp_line
			(start -0.12065 0.2794)
			(end -0.12065 0.3048)
			(stroke
				(width 0.1)
				(type default)
			)
			(layer "F.Fab")
		)
		(fp_line
			(start -0.12065 -0.2794)
			(end 0.12065 -0.2794)
			(stroke
				(width 0.1)
				(type default)
			)
			(layer "F.Fab")
		)
		(fp_line
			(start -0.12065 -0.305054)
			(end -0.12065 -0.2794)
			(stroke
				(width 0.1)
				(type default)
			)
			(layer "F.Fab")
		)
		(fp_line
			(start -0.67945 0.3048)
			(end -0.67945 -0.305054)
			(stroke
				(width 0.1)
				(type default)
			)
			(layer "F.Fab")
		)
		(fp_line
			(start -0.67945 -0.305054)
			(end -0.12065 -0.305054)
			(stroke
				(width 0.1)
				(type default)
			)
			(layer "F.Fab")
		)
		(pad "1" smd circle
			(at -0.40005 0 180)
			(size 0 0)
			(layers "F.Cu" "F.Mask" "F.Paste")
			(net "P12V_AUX")
		)
		(pad "2" smd circle
			(at 0.40005 0 180)
			(size 0 0)
			(layers "F.Cu" "F.Mask" "F.Paste")
			(net "GND")
		)
	)
)
